(kicad_pcb
	(version 20241229)
	(generator "pcbnew")
	(generator_version "9.0")
	(general
		(thickness 1.62)
		(legacy_teardrops no)
	)
	(paper "A3")
	(title_block
		(title "COM Express 7 Baseboard")
		(date "2025-02-04")
		(rev "1.1.2")
		(company "Antmicro Ltd")
		(comment 1 "www.antmicro.com")
		(comment 9 "footprints 372-374 of 802")
	)
	(layers
		(0 "F.Cu" signal)
		(4 "In1.Cu" signal)
		(6 "In2.Cu" signal)
		(8 "In3.Cu" signal)
		(10 "In4.Cu" signal)
		(12 "In5.Cu" signal)
		(14 "In6.Cu" signal)
		(2 "B.Cu" signal)
		(9 "F.Adhes" user "F.Adhesive")
		(11 "B.Adhes" user "B.Adhesive")
		(13 "F.Paste" user)
		(15 "B.Paste" user)
		(5 "F.SilkS" user "F.Silkscreen")
		(7 "B.SilkS" user "B.Silkscreen")
		(1 "F.Mask" user)
		(3 "B.Mask" user)
		(17 "Dwgs.User" user "User.Drawings")
		(19 "Cmts.User" user "User.Comments")
		(21 "Eco1.User" user "User.Eco1")
		(23 "Eco2.User" user "User.Eco2")
		(25 "Edge.Cuts" user)
		(27 "Margin" user)
		(31 "F.CrtYd" user "F.Courtyard")
		(29 "B.CrtYd" user "B.Courtyard")
		(35 "F.Fab" user)
		(33 "B.Fab" user)
	)
	(footprint "antmicro-footprints:PinHeader_1x3_P2.54mm_Drill1.1mm"
		(layer "F.Cu")
		(at 216.42 70.61)
		(property "Reference" "J13"
			(at 7.67 1.36 90)
			(layer "F.SilkS")
			(effects
				(font
					(size 0.7 0.7)
					(thickness 0.15)
				)
				(justify left bottom)
			)
		)
		(property "Value" "PinHeader_1x3_P2.54mm_Drill1.1mm"
			(at -1.6 2.7 0)
			(layer "F.Fab")
			(effects
				(font
					(size 0.7 0.7)
					(thickness 0.15)
				)
				(justify left bottom)
			)
		)
		(property "Datasheet" "https://katalog.we-online.de/em/datasheet/6130xx11121.pdf"
			(at 0 0 0)
			(layer "F.Fab")
			(hide yes)
			(effects
				(font
					(size 1.27 1.27)
					(thickness 0.15)
				)
			)
		)
		(property "Author" "Antmicro"
			(at 0 0 0)
			(layer "F.Fab")
			(hide yes)
			(effects
				(font
					(size 1 1)
					(thickness 0.15)
				)
			)
		)
		(property "License" "Apache-2.0"
			(at 0 0 0)
			(layer "F.Fab")
			(hide yes)
			(effects
				(font
					(size 1 1)
					(thickness 0.15)
				)
			)
		)
		(property "MPN" "61300311121"
			(at 0 0 0)
			(layer "F.Fab")
			(hide yes)
			(effects
				(font
					(size 1 1)
					(thickness 0.15)
				)
			)
		)
		(property "Manufacturer" "Würth Elektronik"
			(at 0 0 0)
			(layer "F.Fab")
			(hide yes)
			(effects
				(font
					(size 1 1)
					(thickness 0.15)
				)
			)
		)
		(sheetname "Com Express 7 MGMT")
		(sheetfile "com_express_7_mgmt.kicad_sch")
		(attr through_hole)
		(fp_line
			(start -1.401 -1.401)
			(end -1.401 -0.902)
			(stroke
				(width 0.15)
				(type solid)
			)
			(layer "F.SilkS")
		)
		(fp_line
			(start -1.401 -1.401)
			(end -0.902 -1.401)
			(stroke
				(width 0.15)
				(type solid)
			)
			(layer "F.SilkS")
		)
		(fp_line
			(start -1.401 1.398)
			(end -1.401 0.9)
			(stroke
				(width 0.15)
				(type solid)
			)
			(layer "F.SilkS")
		)
		(fp_line
			(start -1.401 1.398)
			(end -0.902 1.398)
			(stroke
				(width 0.15)
				(type solid)
			)
			(layer "F.SilkS")
		)
		(fp_line
			(start 6.499 -1.401)
			(end 5.999 -1.401)
			(stroke
				(width 0.15)
				(type solid)
			)
			(layer "F.SilkS")
		)
		(fp_line
			(start 6.499 -1.401)
			(end 6.499 -0.902)
			(stroke
				(width 0.15)
				(type solid)
			)
			(layer "F.SilkS")
		)
		(fp_line
			(start 6.499 1.398)
			(end 5.999 1.398)
			(stroke
				(width 0.15)
				(type solid)
			)
			(layer "F.SilkS")
		)
		(fp_line
			(start 6.499 1.398)
			(end 6.499 0.9)
			(stroke
				(width 0.15)
				(type solid)
			)
			(layer "F.SilkS")
		)
		(fp_line
			(start -1.52 -1.52)
			(end -1.52 1.5)
			(stroke
				(width 0.05)
				(type solid)
			)
			(layer "F.CrtYd")
		)
		(fp_line
			(start -1.52 -1.52)
			(end 6.58 -1.52)
			(stroke
				(width 0.05)
				(type solid)
			)
			(layer "F.CrtYd")
		)
		(fp_line
			(start -1.52 1.5)
			(end 6.58 1.5)
			(stroke
				(width 0.05)
				(type solid)
			)
			(layer "F.CrtYd")
		)
		(fp_line
			(start 6.58 -1.52)
			(end 6.58 1.5)
			(stroke
				(width 0.05)
				(type solid)
			)
			(layer "F.CrtYd")
		)
		(fp_line
			(start -1.27 -1.27)
			(end -1.27 1.269)
			(stroke
				(width 0.15)
				(type solid)
			)
			(layer "F.Fab")
		)
		(fp_line
			(start -1.27 -1.27)
			(end 6.349 -1.27)
			(stroke
				(width 0.15)
				(type solid)
			)
			(layer "F.Fab")
		)
		(fp_line
			(start -1.27 1.269)
			(end 6.349 1.269)
			(stroke
				(width 0.15)
				(type solid)
			)
			(layer "F.Fab")
		)
		(fp_line
			(start 6.349 -1.27)
			(end 6.349 1.269)
			(stroke
				(width 0.15)
				(type solid)
			)
			(layer "F.Fab")
		)
		(pad "1" thru_hole rect
			(at 0 0)
			(size 1.7 1.7)
			(drill 1.1)
			(layers "*.Cu" "*.Mask")
			(remove_unused_layers no)
			(net 523 "Net-(J13-Pad1)")
			(pintype "passive")
			(teardrops
				(best_length_ratio 0.2)
				(max_length 1)
				(best_width_ratio 0.9)
				(max_width 2)
				(curved_edges yes)
				(filter_ratio 0.9)
				(enabled yes)
				(allow_two_segments yes)
				(prefer_zone_connections yes)
			)
		)
		(pad "2" thru_hole circle
			(at 2.539 0)
			(size 1.7 1.7)
			(drill 1.1)
			(layers "*.Cu" "*.Mask")
			(remove_unused_layers no)
			(net 315 "Net-(J12H-VCC_RTC)")
			(pintype "passive")
			(teardrops
				(best_length_ratio 0.4)
				(max_length 1)
				(best_width_ratio 0.9)
				(max_width 2)
				(curved_edges yes)
				(filter_ratio 0.9)
				(enabled yes)
				(allow_two_segments yes)
				(prefer_zone_connections yes)
			)
		)
		(pad "3" thru_hole circle
			(at 5.078 0)
			(size 1.7 1.7)
			(drill 1.1)
			(layers "*.Cu" "*.Mask")
			(remove_unused_layers no)
			(net 135 "Net-(D19-Pad3)")
			(pintype "passive")
			(teardrops
				(best_length_ratio 0.4)
				(max_length 1)
				(best_width_ratio 0.9)
				(max_width 2)
				(curved_edges yes)
				(filter_ratio 0.9)
				(enabled yes)
				(allow_two_segments yes)
				(prefer_zone_connections yes)
			)
		)
	)
	(footprint "antmicro-footprints:Spacer_Drill3.7mm_H5mm_9774050151R"
		(layer "F.Cu")
		(at 278.93 80.8 90)
		(descr "Spacer M=3 h=5mm fi=5.1mm")
		(property "Reference" "H9"
			(at 0 -3.2 90)
			(layer "F.SilkS")
			(hide yes)
			(effects
				(font
					(size 0.7 0.7)
					(thickness 0.15)
				)
				(justify left bottom)
			)
		)
		(property "Value" "Spacer_Drill3.7mm_H5mm_9774050151R"
			(at 0 4 90)
			(layer "F.Fab")
			(effects
				(font
					(size 0.7 0.7)
					(thickness 0.15)
				)
				(justify left bottom)
			)
		)
		(property "Datasheet" "https://www.we-online.com/catalog/datasheet/9774050151.pdf"
			(at 0 0 90)
			(layer "F.Fab")
			(hide yes)
			(effects
				(font
					(size 1.27 1.27)
					(thickness 0.15)
				)
			)
		)
		(property "Author" "Antmicro"
			(at 359.74 -198.12 0)
			(layer "F.Fab")
			(hide yes)
			(effects
				(font
					(size 1 1)
					(thickness 0.15)
				)
			)
		)
		(property "License" "Apache-2.0"
			(at 359.74 -198.12 0)
			(layer "F.Fab")
			(hide yes)
			(effects
				(font
					(size 1 1)
					(thickness 0.15)
				)
			)
		)
		(property "MPN" "9774050151R"
			(at 359.74 -198.12 0)
			(layer "F.Fab")
			(hide yes)
			(effects
				(font
					(size 1 1)
					(thickness 0.15)
				)
			)
		)
		(property "Manufacturer" "Würth Elektronik"
			(at 359.74 -198.12 0)
			(layer "F.Fab")
			(hide yes)
			(effects
				(font
					(size 1 1)
					(thickness 0.15)
				)
			)
		)
		(sheetname "Com Express 7 Interfaces")
		(sheetfile "com_express_7_interfaces.kicad_sch")
		(solder_paste_margin_ratio -1)
		(attr smd)
		(fp_circle
			(center 0 0)
			(end 3.05 0)
			(stroke
				(width 0.05)
				(type solid)
			)
			(fill no)
			(layer "F.CrtYd")
		)
		(fp_circle
			(center 0 0)
			(end 2.6 0)
			(stroke
				(width 0.15)
				(type solid)
			)
			(fill no)
			(layer "F.Fab")
		)
		(pad "" smd custom
			(at -1.7 -1.7 90)
			(size 0.62 0.62)
			(layers "F.Paste")
			(thermal_bridge_angle 90)
			(options
				(clearance outline)
				(anchor circle)
			)
			(primitives
				(gr_arc
					(start -0.250195 1.279127)
					(mid 0.285453 0.294389)
					(end 1.266786 -0.24747)
					(width 0.2)
				)
				(gr_arc
					(start -0.34334 1.279127)
					(mid 0.218448 0.232561)
					(end 1.259603 -0.339191)
					(width 0.2)
				)
				(gr_arc
					(start -0.436309 1.279127)
					(mid 0.152481 0.169693)
					(end 1.255279 -0.431435)
					(width 0.2)
				)
				(gr_arc
					(start -0.529126 1.279127)
					(mid 0.087542 0.105784)
					(end 1.253811 -0.524161)
					(width 0.2)
				)
				(gr_arc
					(start -0.621807 1.279127)
					(mid 0.0309 0.033527)
					(end 1.275473 -0.621136)
					(width 0.2)
				)
				(gr_arc
					(start -0.71437 1.279127)
					(mid -0.037758 -0.026651)
					(end 1.263664 -0.711602)
					(width 0.2)
				)
				(gr_arc
					(start -0.806826 1.279127)
					(mid -0.105837 -0.087395)
					(end 1.253435 -0.802342)
					(width 0.2)
				)
				(gr_arc
					(start -0.899187 1.279127)
					(mid -0.165236 -0.156885)
					(end 1.267475 -0.897258)
					(width 0.2)
				)
				(gr_arc
					(start -0.991463 1.279127)
					(mid -0.228522 -0.222449)
					(end 1.270645 -0.990112)
					(width 0.2)
				)
				(gr_arc
					(start -1.083663 1.279127)
					(mid -0.294507 -0.285313)
					(end 1.266278 -1.081674)
					(width 0.2)
				)
				(gr_line
					(start 1.279127 -0.250195)
					(end 1.279127 -1.083663)
					(width 0.2)
				)
				(gr_line
					(start -0.250195 1.279127)
					(end -1.083663 1.279127)
					(width 0.2)
				)
			)
			(teardrops
				(best_length_ratio 0.2)
				(max_length 1)
				(best_width_ratio 0.9)
				(max_width 2)
				(curved_edges yes)
				(filter_ratio 0.9)
				(enabled yes)
				(allow_two_segments yes)
				(prefer_zone_connections yes)
			)
		)
		(pad "" smd custom
			(at -1.7 1.7 180)
			(size 0.62 0.62)
			(layers "F.Paste")
			(thermal_bridge_angle 90)
			(options
				(clearance outline)
				(anchor circle)
			)
			(primitives
				(gr_arc
					(start -0.250195 1.279127)
					(mid 0.285453 0.294389)
					(end 1.266786 -0.24747)
					(width 0.2)
				)
				(gr_arc
					(start -0.34334 1.279127)
					(mid 0.218448 0.232561)
					(end 1.259603 -0.339191)
					(width 0.2)
				)
				(gr_arc
					(start -0.436309 1.279127)
					(mid 0.152481 0.169693)
					(end 1.255279 -0.431435)
					(width 0.2)
				)
				(gr_arc
					(start -0.529126 1.279127)
					(mid 0.087542 0.105784)
					(end 1.253811 -0.524161)
					(width 0.2)
				)
				(gr_arc
					(start -0.621807 1.279127)
					(mid 0.0309 0.033527)
					(end 1.275473 -0.621136)
					(width 0.2)
				)
				(gr_arc
					(start -0.71437 1.279127)
					(mid -0.037758 -0.026651)
					(end 1.263664 -0.711602)
					(width 0.2)
				)
				(gr_arc
					(start -0.806826 1.279127)
					(mid -0.105837 -0.087395)
					(end 1.253435 -0.802342)
					(width 0.2)
				)
				(gr_arc
					(start -0.899187 1.279127)
					(mid -0.165236 -0.156885)
					(end 1.267475 -0.897258)
					(width 0.2)
				)
				(gr_arc
					(start -0.991463 1.279127)
					(mid -0.228522 -0.222449)
					(end 1.270645 -0.990112)
					(width 0.2)
				)
				(gr_arc
					(start -1.083663 1.279127)
					(mid -0.294507 -0.285313)
					(end 1.266278 -1.081674)
					(width 0.2)
				)
				(gr_line
					(start 1.279127 -0.250195)
					(end 1.279127 -1.083663)
					(width 0.2)
				)
				(gr_line
					(start -0.250195 1.279127)
					(end -1.083663 1.279127)
					(width 0.2)
				)
			)
			(teardrops
				(best_length_ratio 0.2)
				(max_length 1)
				(best_width_ratio 0.9)
				(max_width 2)
				(curved_edges yes)
				(filter_ratio 0.9)
				(enabled yes)
				(allow_two_segments yes)
				(prefer_zone_connections yes)
			)
		)
		(pad "" smd custom
			(at 1.7 -1.7)
			(size 0.62 0.62)
			(layers "F.Paste")
			(thermal_bridge_angle 90)
			(options
				(clearance outline)
				(anchor circle)
			)
			(primitives
				(gr_arc
					(start -0.250195 1.279127)
					(mid 0.285453 0.294389)
					(end 1.266786 -0.24747)
					(width 0.2)
				)
				(gr_arc
					(start -0.34334 1.279127)
					(mid 0.218448 0.232561)
					(end 1.259603 -0.339191)
					(width 0.2)
				)
				(gr_arc
					(start -0.436309 1.279127)
					(mid 0.152481 0.169693)
					(end 1.255279 -0.431435)
					(width 0.2)
				)
				(gr_arc
					(start -0.529126 1.279127)
					(mid 0.087542 0.105784)
					(end 1.253811 -0.524161)
					(width 0.2)
				)
				(gr_arc
					(start -0.621807 1.279127)
					(mid 0.0309 0.033527)
					(end 1.275473 -0.621136)
					(width 0.2)
				)
				(gr_arc
					(start -0.71437 1.279127)
					(mid -0.037758 -0.026651)
					(end 1.263664 -0.711602)
					(width 0.2)
				)
				(gr_arc
					(start -0.806826 1.279127)
					(mid -0.105837 -0.087395)
					(end 1.253435 -0.802342)
					(width 0.2)
				)
				(gr_arc
					(start -0.899187 1.279127)
					(mid -0.165236 -0.156885)
					(end 1.267475 -0.897258)
					(width 0.2)
				)
				(gr_arc
					(start -0.991463 1.279127)
					(mid -0.228522 -0.222449)
					(end 1.270645 -0.990112)
					(width 0.2)
				)
				(gr_arc
					(start -1.083663 1.279127)
					(mid -0.294507 -0.285313)
					(end 1.266278 -1.081674)
					(width 0.2)
				)
				(gr_line
					(start 1.279127 -0.250195)
					(end 1.279127 -1.083663)
					(width 0.2)
				)
				(gr_line
					(start -0.250195 1.279127)
					(end -1.083663 1.279127)
					(width 0.2)
				)
			)
			(teardrops
				(best_length_ratio 0.2)
				(max_length 1)
				(best_width_ratio 0.9)
				(max_width 2)
				(curved_edges yes)
				(filter_ratio 0.9)
				(enabled yes)
				(allow_two_segments yes)
				(prefer_zone_connections yes)
			)
		)
		(pad "" smd custom
			(at 1.7 1.7 270)
			(size 0.62 0.62)
			(layers "F.Paste")
			(thermal_bridge_angle 90)
			(options
				(clearance outline)
				(anchor circle)
			)
			(primitives
				(gr_arc
					(start -0.250195 1.279127)
					(mid 0.285453 0.294389)
					(end 1.266786 -0.24747)
					(width 0.2)
				)
				(gr_arc
					(start -0.34334 1.279127)
					(mid 0.218448 0.232561)
					(end 1.259603 -0.339191)
					(width 0.2)
				)
				(gr_arc
					(start -0.436309 1.279127)
					(mid 0.152481 0.169693)
					(end 1.255279 -0.431435)
					(width 0.2)
				)
				(gr_arc
					(start -0.529126 1.279127)
					(mid 0.087542 0.105784)
					(end 1.253811 -0.524161)
					(width 0.2)
				)
				(gr_arc
					(start -0.621807 1.279127)
					(mid 0.0309 0.033527)
					(end 1.275473 -0.621136)
					(width 0.2)
				)
				(gr_arc
					(start -0.71437 1.279127)
					(mid -0.037758 -0.026651)
					(end 1.263664 -0.711602)
					(width 0.2)
				)
				(gr_arc
					(start -0.806826 1.279127)
					(mid -0.105837 -0.087395)
					(end 1.253435 -0.802342)
					(width 0.2)
				)
				(gr_arc
					(start -0.899187 1.279127)
					(mid -0.165236 -0.156885)
					(end 1.267475 -0.897258)
					(width 0.2)
				)
				(gr_arc
					(start -0.991463 1.279127)
					(mid -0.228522 -0.222449)
					(end 1.270645 -0.990112)
					(width 0.2)
				)
				(gr_arc
					(start -1.083663 1.279127)
					(mid -0.294507 -0.285313)
					(end 1.266278 -1.081674)
					(width 0.2)
				)
				(gr_line
					(start 1.279127 -0.250195)
					(end 1.279127 -1.083663)
					(width 0.2)
				)
				(gr_line
					(start -0.250195 1.279127)
					(end -1.083663 1.279127)
					(width 0.2)
				)
			)
			(teardrops
				(best_length_ratio 0.2)
				(max_length 1)
				(best_width_ratio 0.9)
				(max_width 2)
				(curved_edges yes)
				(filter_ratio 0.9)
				(enabled yes)
				(allow_two_segments yes)
				(prefer_zone_connections yes)
			)
		)
		(pad "1" thru_hole circle
			(at 0 0 90)
			(size 6 6)
			(drill 3.7)
			(layers "*.Cu" "*.Mask")
			(remove_unused_layers no)
			(net 1 "GND")
			(pintype "passive")
			(teardrops
				(best_length_ratio 0.4)
				(max_length 1)
				(best_width_ratio 0.9)
				(max_width 2)
				(curved_edges yes)
				(filter_ratio 0.9)
				(enabled yes)
				(allow_two_segments yes)
				(prefer_zone_connections yes)
			)
		)
	)
	(footprint "antmicro-footprints:R_0201"
		(layer "F.Cu")
		(at 146.57 147.935 -90)
		(descr "Resistor SMD 0201")
		(tags "resistor SMD 0201")
		(property "Reference" "R278"
			(at 3.625 -0.28 90)
			(layer "F.SilkS")
			(effects
				(font
					(size 0.7 0.7)
					(thickness 0.15)
				)
				(justify right bottom)
			)
		)
		(property "Value" "R_0R_0201"
			(at 0 1.25 90)
			(layer "F.Fab")
			(effects
				(font
					(size 0.7 0.7)
					(thickness 0.15)
				)
				(justify right bottom)
			)
		)
		(property "Datasheet" "https://www.bourns.com/docs/product-datasheets/cr.pdf"
			(at 0 0 270)
			(layer "F.Fab")
			(hide yes)
			(effects
				(font
					(size 1.27 1.27)
					(thickness 0.15)
				)
			)
		)
		(property "Author" "Antmicro"
			(at -1.365 294.505 0)
			(layer "F.Fab")
			(hide yes)
			(effects
				(font
					(size 1 1)
					(thickness 0.15)
				)
			)
		)
		(property "License" "Apache-2.0"
			(at -1.365 294.505 0)
			(layer "F.Fab")
			(hide yes)
			(effects
				(font
					(size 1 1)
					(thickness 0.15)
				)
			)
		)
		(property "MPN" "CR0201-FX-0R00GLF"
			(at -1.365 294.505 0)
			(layer "F.Fab")
			(hide yes)
			(effects
				(font
					(size 1 1)
					(thickness 0.15)
				)
			)
		)
		(property "Manufacturer" "Bourns"
			(at -1.365 294.505 0)
			(layer "F.Fab")
			(hide yes)
			(effects
				(font
					(size 1 1)
					(thickness 0.15)
				)
			)
		)
		(property "Tolerance" "1%"
			(at -1.365 294.505 0)
			(layer "F.Fab")
			(hide yes)
			(effects
				(font
					(size 1 1)
					(thickness 0.15)
				)
			)
		)
		(property "Val" "0R"
			(at -1.365 294.505 0)
			(layer "F.Fab")
			(hide yes)
			(effects
				(font
					(size 1 1)
					(thickness 0.15)
				)
			)
		)
		(sheetname "KR to SFI #1")
		(sheetfile "kr_sfi.kicad_sch")
		(attr smd dnp)
		(fp_rect
			(start -0.7 -0.35)
			(end 0.7 0.35)
			(stroke
				(width 0.05)
				(type default)
			)
			(fill no)
			(layer "F.CrtYd")
		)
		(fp_rect
			(start -0.3 -0.15)
			(end 0.298 0.148)
			(stroke
				(width 0.15)
				(type solid)
			)
			(fill no)
			(layer "F.Fab")
		)
		(pad "" smd roundrect
			(at -0.346 0 270)
			(size 0.318 0.36)
			(layers "F.Paste")
			(roundrect_rratio 0.25)
			(teardrops
				(best_length_ratio 0.2)
				(max_length 1)
				(best_width_ratio 0.9)
				(max_width 2)
				(curved_edges yes)
				(filter_ratio 0.9)
				(enabled yes)
				(allow_two_segments yes)
				(prefer_zone_connections yes)
			)
		)
		(pad "" smd roundrect
			(at 0.344 0 270)
			(size 0.318 0.36)
			(layers "F.Paste")
			(roundrect_rratio 0.25)
			(teardrops
				(best_length_ratio 0.2)
				(max_length 1)
				(best_width_ratio 0.9)
				(max_width 2)
				(curved_edges yes)
				(filter_ratio 0.9)
				(enabled yes)
				(allow_two_segments yes)
				(prefer_zone_connections yes)
			)
		)
		(pad "1" smd roundrect
			(at -0.32 0 270)
			(size 0.46 0.4)
			(layers "F.Cu" "F.Mask")
			(roundrect_rratio 0.25)
			(net 173 "/2xSFP+/SFI0.TX-")
			(pintype "passive")
			(teardrops
				(best_length_ratio 0.2)
				(max_length 1)
				(best_width_ratio 0.9)
				(max_width 2)
				(curved_edges yes)
				(filter_ratio 0.9)
				(enabled yes)
				(allow_two_segments yes)
				(prefer_zone_connections yes)
			)
		)
		(pad "2" smd roundrect
			(at 0.32 0 270)
			(size 0.46 0.4)
			(layers "F.Cu" "F.Mask")
			(roundrect_rratio 0.25)
			(net 948 "/2xSFP+/KR to SFI #1/BYP_TX-")
			(pintype "passive")
			(teardrops
				(best_length_ratio 0.2)
				(max_length 1)
				(best_width_ratio 0.9)
				(max_width 2)
				(curved_edges yes)
				(filter_ratio 0.9)
				(enabled yes)
				(allow_two_segments yes)
				(prefer_zone_connections yes)
			)
		)
	)
)
